# T6G (Grand Teton) — schematic netlist excerpt (pin names and nets, part order shuffled) for the footprints in the layout excerpt that follows; sources: Cadence DE-HDL packaged netlist, KiCad conversion of 04192023_DAF0TMB3IC0_F0TG_MB_C_brd_V02_OCP.brd

J33  SCONN288_DDR506112002KQ  IO  pkg DDR288S_1-1VXC  page 103
  VIN_BULK0  = P12V_MEM_CPU1
  RFU0  = NC
  VIN_MGMT  = P3V3_AUX
  HSCL  = I3C_SPD_DDRF_CPU1_SCL
  HSDA  = I3C_SPD_DDRF_CPU1_SDA
  VSS0  = GND
  DQ0_A  = M_F_CPU1_SA_DQ<0>
  VSS1  = GND
  DQ1_A  = M_F_CPU1_SA_DQ<1>
  VSS2  = GND
  DQS0_A_T  = M_F_CPU1_SA_DQS_DP<0>
  DQS0_A_C  = M_F_CPU1_SA_DQS_DN<0>
  VSS3  = GND
  DQ4_A  = M_F_CPU1_SA_DQ<4>
  VSS4  = GND
  DQ5_A  = M_F_CPU1_SA_DQ<5>
  VSS5  = GND
  DQ8_A  = M_F_CPU1_SA_DQ<8>
  VSS6  = GND
  DQ9_A  = M_F_CPU1_SA_DQ<9>
  VSS7  = GND
  DQS1_A_T  = M_F_CPU1_SA_DQS_DP<1>
  DQS1_A_C  = M_F_CPU1_SA_DQS_DN<1>
  VSS8  = GND
  DQ12_A  = M_F_CPU1_SA_DQ<12>
  VSS9  = GND
  DQ13_A  = M_F_CPU1_SA_DQ<13>
  VSS10  = GND
  DQ16_A  = M_F_CPU1_SA_DQ<16>
  VSS11  = GND
  DQ17_A  = M_F_CPU1_SA_DQ<17>
  VSS12  = GND
  DQS2_A_T  = M_F_CPU1_SA_DQS_DP<2>
  DQS2_A_C  = M_F_CPU1_SA_DQS_DN<2>
  VSS13  = GND
  DQ20_A  = M_F_CPU1_SA_DQ<20>
  VSS14  = GND
  DQ21_A  = M_F_CPU1_SA_DQ<21>
  VSS15  = GND
  DQ24_A  = M_F_CPU1_SA_DQ<24>
  VSS16  = GND
  DQ25_A  = M_F_CPU1_SA_DQ<25>
  VSS17  = GND
  DQS3_A_T  = M_F_CPU1_SA_DQS_DP<3>
  DQS3_A_C  = M_F_CPU1_SA_DQS_DN<3>
  VSS18  = GND
  DQ28_A  = M_F_CPU1_SA_DQ<28>
  VSS19  = GND
  DQ29_A  = M_F_CPU1_SA_DQ<29>
  VSS20  = GND
  CB0_A  = M_F_CPU1_SA_CB<0>
  VSS21  = GND
  CB1_A  = M_F_CPU1_SA_CB<1>
  VSS22  = GND
  DQS4_A_T  = M_F_CPU1_SA_DQS_DP<4>
  DQS4_A_C  = M_F_CPU1_SA_DQS_DN<4>
  VSS23  = GND
  CB4_A  = M_F_CPU1_SA_CB<4>
  VSS24  = GND
  CB5_A  = M_F_CPU1_SA_CB<5>
  VSS25  = GND
  ALERT_N  = M_F_CPU1_ALERT_N
  VSS26  = GND
  CS0_A_N  = M_F_CPU1_SA_CS_N<0>
  VSS27  = GND
  CA0_A  = M_F_CPU1_SA_CA<0>
  VSS28  = GND
  CA2_A  = M_F_CPU1_SA_CA<2>
  VSS29  = GND
  CA4_A  = M_F_CPU1_SA_CA<4>
  VSS30  = GND
  CA6_A  = M_F_CPU1_SA_CA<6>
  VSS31  = GND
  PAR_A  = M_F_CPU1_SA_PAR
  VSS32  = GND
  CA0_B  = M_F_CPU1_SB_CA<0>
  VSS33  = GND
  CA2_B  = M_F_CPU1_SB_CA<2>
  VSS34  = GND
  CA4_B  = M_F_CPU1_SB_CA<4>
  VSS35  = GND
  CA6_B  = M_F_CPU1_SB_CA<6>
  VSS36  = GND
  CS0_B_N  = M_F_CPU1_SB_CS_N<0>
  VSS37  = GND
  \lbd||rsp_a_n\  = M_F_CPU1_SA_RSP<0>
  \lbs||rsp_b_n\  = M_F_CPU1_SB_RSP<0>
  VSS38  = GND
  CB4_B  = M_F_CPU1_SB_CB<4>
  VSS39  = GND
  CB5_B  = M_F_CPU1_SB_CB<5>
  VSS40  = GND
  \dqs9_b_t||tdqs9_b_t||dbi4_b_n\  = M_F_CPU1_SB_DQS_DP<9>
  \dqs9_b_c||tdqs9_b_c\  = M_F_CPU1_SB_DQS_DN<9>
  VSS41  = GND
  CB0_B  = M_F_CPU1_SB_CB<0>
  VSS42  = GND
  CB1_B  = M_F_CPU1_SB_CB<1>
  VSS43  = GND
  DQ0_B  = M_F_CPU1_SB_DQ<0>
  VSS44  = GND
  DQ1_B  = M_F_CPU1_SB_DQ<1>
  VSS45  = GND
  DQS0_B_T  = M_F_CPU1_SB_DQS_DP<0>
  DQS0_B_C  = M_F_CPU1_SB_DQS_DN<0>
  VSS46  = GND
  DQ4_B  = M_F_CPU1_SB_DQ<4>
  VSS47  = GND
  DQ5_B  = M_F_CPU1_SB_DQ<5>
  VSS48  = GND
  DQ8_B  = M_F_CPU1_SB_DQ<8>
  VSS49  = GND
  DQ9_B  = M_F_CPU1_SB_DQ<9>
  VSS50  = GND
  DQS1_B_T  = M_F_CPU1_SB_DQS_DP<1>
  DQS1_B_C  = M_F_CPU1_SB_DQS_DN<1>
  VSS51  = GND
  DQ12_B  = M_F_CPU1_SB_DQ<12>
  VSS52  = GND
  DQ13_B  = M_F_CPU1_SB_DQ<13>
  VSS53  = GND
  DQ16_B  = M_F_CPU1_SB_DQ<16>
  VSS54  = GND
  DQ17_B  = M_F_CPU1_SB_DQ<17>
  VSS55  = GND
  DQS2_B_T  = M_F_CPU1_SB_DQS_DP<2>
  DQS2_B_C  = M_F_CPU1_SB_DQS_DN<2>
  VSS56  = GND
  DQ20_B  = M_F_CPU1_SB_DQ<20>
  VSS57  = GND
  DQ21_B  = M_F_CPU1_SB_DQ<21>
  VSS58  = GND
  DQ24_B  = M_F_CPU1_SB_DQ<24>
  VSS59  = GND
  DQ25_B  = M_F_CPU1_SB_DQ<25>
  VSS60  = GND
  DQS3_B_T  = M_F_CPU1_SB_DQS_DP<3>
  DQS3_B_C  = M_F_CPU1_SB_DQS_DN<3>
  VSS61  = GND
  DQ28_B  = M_F_CPU1_SB_DQ<28>
  VSS62  = GND
  DQ29_B  = M_F_CPU1_SB_DQ<29>
  VSS63  = GND
  RFU1  = NC
  VIN_BULK1  = P12V_MEM_CPU1
  VIN_BULK2  = P12V_MEM_CPU1
  \pwr_good||fail_n\  = PWRGD_CHF_CPU1_DIMM
  HAS  = PD_CHF_CPU1_DIMM_SAA
  RFU2  = NC
  RFU3  = NC
  VSS64  = GND
  DQ2_A  = M_F_CPU1_SA_DQ<2>
  VSS65  = GND
  DQ3_A  = M_F_CPU1_SA_DQ<3>
  VSS66  = GND
  \dqs5_a_c||tdqs5_a_c||dqs5_a_t||tdqs5_a_t\  = M_F_CPU1_SA_DQS_DN<5>
  \dqs5_a_t||tdqs5_a_t\  = M_F_CPU1_SA_DQS_DP<5>
  VSS67  = GND
  DQ6_A  = M_F_CPU1_SA_DQ<6>
  VSS68  = GND
  DQ7_A  = M_F_CPU1_SA_DQ<7>
  VSS69  = GND
  DQ10_A  = M_F_CPU1_SA_DQ<10>
  VSS70  = GND
  DQ11_A  = M_F_CPU1_SA_DQ<11>
  VSS71  = GND
  \dqs6_a_c||tdqs6_a_c||dqs6_a_t||tdqs6_a_t\  = M_F_CPU1_SA_DQS_DN<6>
  \dqs6_a_t||tdqs6_a_t\  = M_F_CPU1_SA_DQS_DP<6>
  VSS72  = GND
  DQ14_A  = M_F_CPU1_SA_DQ<14>
  VSS73  = GND
  DQ15_A  = M_F_CPU1_SA_DQ<15>
  VSS74  = GND
  DQ18_A  = M_F_CPU1_SA_DQ<18>
  VSS75  = GND
  DQ19_A  = M_F_CPU1_SA_DQ<19>
  VSS76  = GND
  \dqs7_a_c||tdqs7_a_c\  = M_F_CPU1_SA_DQS_DN<7>
  \dqs7_a_t||tdqs7_a_t\  = M_F_CPU1_SA_DQS_DP<7>
  VSS77  = GND
  DQ22_A  = M_F_CPU1_SA_DQ<22>
  VSS78  = GND
  DQ23_A  = M_F_CPU1_SA_DQ<23>
  VSS79  = GND
  DQ26_A  = M_F_CPU1_SA_DQ<26>
  VSS80  = GND
  DQ27_A  = M_F_CPU1_SA_DQ<27>
  VSS81  = GND
  \dqs8_a_c||tdqs8_a_c\  = M_F_CPU1_SA_DQS_DN<8>
  \dqs8_a_t||tdqs8_a_t\  = M_F_CPU1_SA_DQS_DP<8>
  VSS82  = GND
  DQ30_A  = M_F_CPU1_SA_DQ<30>
  VSS83  = GND
  DQ31_A  = M_F_CPU1_SA_DQ<31>
  VSS84  = GND
  CB2_A  = M_F_CPU1_SA_CB<2>
  VSS85  = GND
  CB3_A  = M_F_CPU1_SA_CB<3>
  VSS86  = GND
  \dqs9_a_c||tdqs9_a_c\  = M_F_CPU1_SA_DQS_DN<9>
  \dqs9_a_t||tdqs9_a_t\  = M_F_CPU1_SA_DQS_DP<9>
  VSS87  = GND
  CB6_A  = M_F_CPU1_SA_CB<6>
  VSS88  = GND
  CB7_A  = M_F_CPU1_SA_CB<7>
  VSS89  = GND
  RESET_N  = M_F_CPU1_RESET_N
  VSS90  = GND
  CS1_A_N  = M_F_CPU1_SA_CS_N<1>
  VSS91  = GND
  CA1_A  = M_F_CPU1_SA_CA<1>
  VSS92  = GND
  CA3_A  = M_F_CPU1_SA_CA<3>
  VSS93  = GND
  CA5_A  = M_F_CPU1_SA_CA<5>
  VSS94  = GND
  CK_T  = M_F_CPU1_CLK_DP<0>
  CK_C  = M_F_CPU1_CLK_DN<0>
  VSS95  = GND
  RFU4  = NC
  CA1_B  = M_F_CPU1_SB_CA<1>
  VSS96  = GND
  CA3_B  = M_F_CPU1_SB_CA<3>
  VSS97  = GND
  CA5_B  = M_F_CPU1_SB_CA<5>
  VSS98  = GND
  PAR_B  = M_F_CPU1_SB_PAR
  VSS99  = GND
  CS1_B_N  = M_F_CPU1_SB_CS_N<1>
  VSS100  = GND
  RFU5  = NC
  RFU6  = NC
  VSS101  = GND
  CB6_B  = M_F_CPU1_SB_CB<6>
  VSS102  = GND
  CB7_B  = M_F_CPU1_SB_CB<7>
  VSS103  = GND
  DQS4_B_C  = M_F_CPU1_SB_DQS_DN<4>
  DQS4_B_T  = M_F_CPU1_SB_DQS_DP<4>
  VSS104  = GND
  CB2_B  = M_F_CPU1_SB_CB<2>
  VSS105  = GND
  CB3_B  = M_F_CPU1_SB_CB<3>
  VSS106  = GND
  DQ2_B  = M_F_CPU1_SB_DQ<2>
  VSS107  = GND
  DQ3_B  = M_F_CPU1_SB_DQ<3>
  VSS108  = GND
  \dqs5_b_c||tdqs5_b_c\  = M_F_CPU1_SB_DQS_DN<5>
  \dqs5_b_t||tdqs5_b_t\  = M_F_CPU1_SB_DQS_DP<5>
  VSS109  = GND
  DQ6_B  = M_F_CPU1_SB_DQ<6>
  VSS110  = GND
  DQ7_B  = M_F_CPU1_SB_DQ<7>
  VSS111  = GND
  DQ10_B  = M_F_CPU1_SB_DQ<10>
  VSS112  = GND
  DQ11_B  = M_F_CPU1_SB_DQ<11>
  VSS113  = GND
  \dqs6_b_c||tdqs6_b_c\  = M_F_CPU1_SB_DQS_DN<6>
  \dqs6_b_t||tdqs6_b_t\  = M_F_CPU1_SB_DQS_DP<6>
  VSS114  = GND
  DQ14_B  = M_F_CPU1_SB_DQ<14>
  VSS115  = GND
  DQ15_B  = M_F_CPU1_SB_DQ<15>
  VSS116  = GND
  DQ18_B  = M_F_CPU1_SB_DQ<18>
  VSS117  = GND
  DQ19_B  = M_F_CPU1_SB_DQ<19>
  VSS118  = GND
  \dqs7_b_c||tdqs7_b_c\  = M_F_CPU1_SB_DQS_DN<7>
  \dqs7_b_t||tdqs7_b_t\  = M_F_CPU1_SB_DQS_DP<7>
  VSS119  = GND
  DQ22_B  = M_F_CPU1_SB_DQ<22>
  VSS120  = GND
  DQ23_B  = M_F_CPU1_SB_DQ<23>
  VSS121  = GND
  DQ26_B  = M_F_CPU1_SB_DQ<26>
  VSS122  = GND
  DQ27_B  = M_F_CPU1_SB_DQ<27>
  VSS123  = GND
  \dqs8_b_c||tdqs8_b_c\  = M_F_CPU1_SB_DQS_DN<8>
  \dqs8_b_t||tdqs8_b_t\  = M_F_CPU1_SB_DQS_DP<8>
  VSS124  = GND
  DQ30_B  = M_F_CPU1_SB_DQ<30>
  VSS125  = GND
  DQ31_B  = M_F_CPU1_SB_DQ<31>
  VSS126  = GND
  G1  = GND
  G2  = GND
  G3  = GND

(kicad_pcb
	(version 20260206)
	(generator "pcbnew")
	(generator_version "10.0")
	(general
		(thickness 1.6)
		(legacy_teardrops no)
	)
	(paper "A4")
	(title_block
		(title "04192023_DAF0TMB3IC0_F0TG_MB_C_brd_V02_OCP.brd")
		(comment 1 "Grand Teton / footprint 4248 of 8354 (J33), pads 185-230 of 291")
	)
	(layers
		(0 "F.Cu" signal "TOP")
		(4 "In1.Cu" signal "GND")
		(6 "In2.Cu" signal "IN1")
		(8 "In3.Cu" signal "GND1")
		(10 "In4.Cu" signal "IN2")
		(12 "In5.Cu" signal "GND2")
		(14 "In6.Cu" signal "IN3")
		(16 "In7.Cu" signal "GND3")
		(18 "In8.Cu" signal "VCC")
		(20 "In9.Cu" signal "VCC1")
		(22 "In10.Cu" signal "GND4")
		(24 "In11.Cu" signal "IN4")
		(26 "In12.Cu" signal "GND5")
		(28 "In13.Cu" signal "IN5")
		(30 "In14.Cu" signal "GND6")
		(32 "In15.Cu" signal "IN6")
		(34 "In16.Cu" signal "GND7")
		(2 "B.Cu" signal "BOTTOM")
		(9 "F.Adhes" user "F.Adhesive")
		(11 "B.Adhes" user "B.Adhesive")
		(13 "F.Paste" user "Package Geometry/Pastemask Top")
		(15 "B.Paste" user "Package Geometry/Pastemask Bottom")
		(5 "F.SilkS" user "Ref Des/Silkscreen Top")
		(7 "B.SilkS" user "Ref Des/Silkscreen Bottom")
		(1 "F.Mask" user "Board Geometry/Soldermask Top")
		(3 "B.Mask" user "Board Geometry/Soldermask Bottom")
		(17 "Dwgs.User" user "User.Drawings")
		(19 "Cmts.User" user "User.Comments")
		(21 "Eco1.User" user "User.Eco1")
		(23 "Eco2.User" user "User.Eco2")
		(25 "Edge.Cuts" user "Board Geometry/Outline")
		(27 "Margin" user)
		(31 "F.CrtYd" user "Package Geometry/Place Bound Top")
		(29 "B.CrtYd" user "Package Geometry/Place Bound Bottom")
		(35 "F.Fab" user "Ref Des/Assembly Top")
		(33 "B.Fab" user "Ref Des/Assembly Bottom")
	)
	(footprint ""
		(layer "F.Cu")
		(at 19.658076 -255.560322 180)
		(property "Reference" "J33"
			(at -1.25984 -82.079846 0)
			(unlocked yes)
			(layer "F.SilkS")
			(effects
				(font
					(size 0.7874 0.5842)
					(thickness 0.1524)
				)
			)
		)
		(property "Value" ""
			(at 0 0 180)
			(layer "F.Fab")
			(effects
				(font
					(size 1.27 1.27)
				)
			)
		)
		(duplicate_pad_numbers_are_jumpers no)
		(pad "185" smd rect
			(at 2.050034 -29.325062 90)
			(size 0.519938 1.4986)
			(layers "F.Cu" "F.Mask" "F.Paste")
			(net "M_F_CPU1_SA_DQ<26>")
		)
		(pad "186" smd rect
			(at 2.050034 -28.474924 90)
			(size 0.519938 1.4986)
			(layers "F.Cu" "F.Mask" "F.Paste")
			(net "GND")
		)
		(pad "187" smd rect
			(at 2.050034 -27.62504 90)
			(size 0.519938 1.4986)
			(layers "F.Cu" "F.Mask" "F.Paste")
			(net "M_F_CPU1_SA_DQ<27>")
		)
		(pad "188" smd rect
			(at 2.050034 -26.774902 90)
			(size 0.519938 1.4986)
			(layers "F.Cu" "F.Mask" "F.Paste")
			(net "GND")
		)
		(pad "189" smd rect
			(at 2.050034 -25.925018 90)
			(size 0.519938 1.4986)
			(layers "F.Cu" "F.Mask" "F.Paste")
			(net "M_F_CPU1_SA_DQS_DN<8>")
		)
		(pad "190" smd rect
			(at 2.050034 -25.07488 90)
			(size 0.519938 1.4986)
			(layers "F.Cu" "F.Mask" "F.Paste")
			(net "M_F_CPU1_SA_DQS_DP<8>")
		)
		(pad "191" smd rect
			(at 2.050034 -24.224996 90)
			(size 0.519938 1.4986)
			(layers "F.Cu" "F.Mask" "F.Paste")
			(net "GND")
		)
		(pad "192" smd rect
			(at 2.050034 -23.375112 90)
			(size 0.519938 1.4986)
			(layers "F.Cu" "F.Mask" "F.Paste")
			(net "M_F_CPU1_SA_DQ<30>")
		)
		(pad "193" smd rect
			(at 2.050034 -22.524974 90)
			(size 0.519938 1.4986)
			(layers "F.Cu" "F.Mask" "F.Paste")
			(net "GND")
		)
		(pad "194" smd rect
			(at 2.050034 -21.67509 90)
			(size 0.519938 1.4986)
			(layers "F.Cu" "F.Mask" "F.Paste")
			(net "M_F_CPU1_SA_DQ<31>")
		)
		(pad "195" smd rect
			(at 2.050034 -20.824952 90)
			(size 0.519938 1.4986)
			(layers "F.Cu" "F.Mask" "F.Paste")
			(net "GND")
		)
		(pad "196" smd rect
			(at 2.050034 -19.975068 90)
			(size 0.519938 1.4986)
			(layers "F.Cu" "F.Mask" "F.Paste")
			(net "M_F_CPU1_SA_CB<2>")
		)
		(pad "197" smd rect
			(at 2.050034 -19.12493 90)
			(size 0.519938 1.4986)
			(layers "F.Cu" "F.Mask" "F.Paste")
			(net "GND")
		)
		(pad "198" smd rect
			(at 2.050034 -18.275046 90)
			(size 0.519938 1.4986)
			(layers "F.Cu" "F.Mask" "F.Paste")
			(net "M_F_CPU1_SA_CB<3>")
		)
		(pad "199" smd rect
			(at 2.050034 -17.424908 90)
			(size 0.519938 1.4986)
			(layers "F.Cu" "F.Mask" "F.Paste")
			(net "GND")
		)
		(pad "200" smd rect
			(at 2.050034 -16.575024 90)
			(size 0.519938 1.4986)
			(layers "F.Cu" "F.Mask" "F.Paste")
			(net "M_F_CPU1_SA_DQS_DN<9>")
		)
		(pad "201" smd rect
			(at 2.050034 -15.724886 90)
			(size 0.519938 1.4986)
			(layers "F.Cu" "F.Mask" "F.Paste")
			(net "M_F_CPU1_SA_DQS_DP<9>")
		)
		(pad "202" smd rect
			(at 2.050034 -14.875002 90)
			(size 0.519938 1.4986)
			(layers "F.Cu" "F.Mask" "F.Paste")
			(net "GND")
		)
		(pad "203" smd rect
			(at 2.050034 -14.025118 90)
			(size 0.519938 1.4986)
			(layers "F.Cu" "F.Mask" "F.Paste")
			(net "M_F_CPU1_SA_CB<6>")
		)
		(pad "204" smd rect
			(at 2.050034 -13.17498 90)
			(size 0.519938 1.4986)
			(layers "F.Cu" "F.Mask" "F.Paste")
			(net "GND")
		)
		(pad "205" smd rect
			(at 2.050034 -12.325096 90)
			(size 0.519938 1.4986)
			(layers "F.Cu" "F.Mask" "F.Paste")
			(net "M_F_CPU1_SA_CB<7>")
		)
		(pad "206" smd rect
			(at 2.050034 -11.474958 90)
			(size 0.519938 1.4986)
			(layers "F.Cu" "F.Mask" "F.Paste")
			(net "GND")
		)
		(pad "207" smd rect
			(at 2.050034 -10.625074 90)
			(size 0.519938 1.4986)
			(layers "F.Cu" "F.Mask" "F.Paste")
			(net "M_F_CPU1_RESET_N")
		)
		(pad "208" smd rect
			(at 2.050034 -9.774936 90)
			(size 0.519938 1.4986)
			(layers "F.Cu" "F.Mask" "F.Paste")
			(net "GND")
		)
		(pad "209" smd rect
			(at 2.050034 -8.925052 90)
			(size 0.519938 1.4986)
			(layers "F.Cu" "F.Mask" "F.Paste")
			(net "M_F_CPU1_SA_CS_N<1>")
		)
		(pad "210" smd rect
			(at 2.050034 -8.074914 90)
			(size 0.519938 1.4986)
			(layers "F.Cu" "F.Mask" "F.Paste")
			(net "GND")
		)
		(pad "211" smd rect
			(at 2.050034 -7.22503 90)
			(size 0.519938 1.4986)
			(layers "F.Cu" "F.Mask" "F.Paste")
			(net "M_F_CPU1_SA_CA<1>")
		)
		(pad "212" smd rect
			(at 2.050034 -6.374892 90)
			(size 0.519938 1.4986)
			(layers "F.Cu" "F.Mask" "F.Paste")
			(net "GND")
		)
		(pad "213" smd rect
			(at 2.050034 -5.525008 90)
			(size 0.519938 1.4986)
			(layers "F.Cu" "F.Mask" "F.Paste")
			(net "M_F_CPU1_SA_CA<3>")
		)
		(pad "214" smd rect
			(at 2.050034 -4.675124 90)
			(size 0.519938 1.4986)
			(layers "F.Cu" "F.Mask" "F.Paste")
			(net "GND")
		)
		(pad "215" smd rect
			(at 2.050034 -3.824986 90)
			(size 0.519938 1.4986)
			(layers "F.Cu" "F.Mask" "F.Paste")
			(net "M_F_CPU1_SA_CA<5>")
		)
		(pad "216" smd rect
			(at 2.050034 -2.975102 90)
			(size 0.519938 1.4986)
			(layers "F.Cu" "F.Mask" "F.Paste")
			(net "GND")
		)
		(pad "217" smd rect
			(at 2.050034 -2.124964 90)
			(size 0.519938 1.4986)
			(layers "F.Cu" "F.Mask" "F.Paste")
			(net "M_F_CPU1_CLK_DP<0>")
		)
		(pad "218" smd rect
			(at 2.050034 -1.27508 90)
			(size 0.519938 1.4986)
			(layers "F.Cu" "F.Mask" "F.Paste")
			(net "M_F_CPU1_CLK_DN<0>")
		)
		(pad "219" smd rect
			(at 2.050034 -0.424942 90)
			(size 0.519938 1.4986)
			(layers "F.Cu" "F.Mask" "F.Paste")
			(net "GND")
		)
		(pad "220" smd rect
			(at 2.050034 5.525008 90)
			(size 0.519938 1.4986)
			(layers "F.Cu" "F.Mask" "F.Paste")
			(net "Net_2330")
		)
		(pad "221" smd rect
			(at 2.050034 6.374892 90)
			(size 0.519938 1.4986)
			(layers "F.Cu" "F.Mask" "F.Paste")
			(net "M_F_CPU1_SB_CA<1>")
		)
		(pad "222" smd rect
			(at 2.050034 7.22503 90)
			(size 0.519938 1.4986)
			(layers "F.Cu" "F.Mask" "F.Paste")
			(net "GND")
		)
		(pad "223" smd rect
			(at 2.050034 8.074914 90)
			(size 0.519938 1.4986)
			(layers "F.Cu" "F.Mask" "F.Paste")
			(net "M_F_CPU1_SB_CA<3>")
		)
		(pad "224" smd rect
			(at 2.050034 8.925052 90)
			(size 0.519938 1.4986)
			(layers "F.Cu" "F.Mask" "F.Paste")
			(net "GND")
		)
		(pad "225" smd rect
			(at 2.050034 9.774936 90)
			(size 0.519938 1.4986)
			(layers "F.Cu" "F.Mask" "F.Paste")
			(net "M_F_CPU1_SB_CA<5>")
		)
		(pad "226" smd rect
			(at 2.050034 10.625074 90)
			(size 0.519938 1.4986)
			(layers "F.Cu" "F.Mask" "F.Paste")
			(net "GND")
		)
		(pad "227" smd rect
			(at 2.050034 11.474958 90)
			(size 0.519938 1.4986)
			(layers "F.Cu" "F.Mask" "F.Paste")
			(net "M_F_CPU1_SB_PAR")
		)
		(pad "228" smd rect
			(at 2.050034 12.325096 90)
			(size 0.519938 1.4986)
			(layers "F.Cu" "F.Mask" "F.Paste")
			(net "GND")
		)
		(pad "229" smd rect
			(at 2.050034 13.17498 90)
			(size 0.519938 1.4986)
			(layers "F.Cu" "F.Mask" "F.Paste")
			(net "M_F_CPU1_SB_CS_N<1>")
		)
		(pad "230" smd rect
			(at 2.050034 14.025118 90)
			(size 0.519938 1.4986)
			(layers "F.Cu" "F.Mask" "F.Paste")
			(net "GND")
		)
	)
)
